(kicad_pcb
	(version 20260206)
	(generator "pcbnew")
	(generator_version "10.0")
	(general
		(thickness 1.6)
		(legacy_teardrops no)
	)
	(paper "A4")
	(title_block
		(title "01162023_DA0F0TEBIF0_F0T_Expander_BD_F_brd_V02_OCP.brd")
		(comment 1 "Grand Teton / footprints 4544-4551 of 9728")
	)
	(layers
		(0 "F.Cu" signal "TOP")
		(4 "In1.Cu" signal "GND")
		(6 "In2.Cu" signal "VCC")
		(8 "In3.Cu" signal "VCC1")
		(10 "In4.Cu" signal "GND1")
		(12 "In5.Cu" signal "IN1")
		(14 "In6.Cu" signal "GND2")
		(16 "In7.Cu" signal "IN2")
		(18 "In8.Cu" signal "GND3")
		(20 "In9.Cu" signal "IN3")
		(22 "In10.Cu" signal "GND4")
		(24 "In11.Cu" signal "IN4")
		(26 "In12.Cu" signal "GND5")
		(28 "In13.Cu" signal "IN5")
		(30 "In14.Cu" signal "GND6")
		(32 "In15.Cu" signal "IN6")
		(34 "In16.Cu" signal "GND7")
		(2 "B.Cu" signal "BOTTOM")
		(9 "F.Adhes" user "F.Adhesive")
		(11 "B.Adhes" user "B.Adhesive")
		(13 "F.Paste" user "Package Geometry/Pastemask Top")
		(15 "B.Paste" user "Package Geometry/Pastemask Bottom")
		(5 "F.SilkS" user "Ref Des/Silkscreen Top")
		(7 "B.SilkS" user "Ref Des/Silkscreen Bottom")
		(1 "F.Mask" user "Board Geometry/Soldermask Top")
		(3 "B.Mask" user "Board Geometry/Soldermask Bottom")
		(17 "Dwgs.User" user "User.Drawings")
		(19 "Cmts.User" user "User.Comments")
		(21 "Eco1.User" user "User.Eco1")
		(23 "Eco2.User" user "User.Eco2")
		(25 "Edge.Cuts" user "Board Geometry/Outline")
		(27 "Margin" user)
		(31 "F.CrtYd" user "Package Geometry/Place Bound Top")
		(29 "B.CrtYd" user "Package Geometry/Place Bound Bottom")
		(35 "F.Fab" user "Ref Des/Assembly Top")
		(33 "B.Fab" user "Ref Des/Assembly Bottom")
	)
	(footprint ""
		(layer "F.Cu")
		(at 376.34926 -290.595812 -90)
		(property "Reference" "C3558"
			(at 0 0 270)
			(layer "F.SilkS")
			(hide yes)
			(effects
				(font
					(size 1.27 1.27)
				)
			)
		)
		(property "Value" ""
			(at 0 0 270)
			(layer "F.Fab")
			(effects
				(font
					(size 1.27 1.27)
				)
			)
		)
		(duplicate_pad_numbers_are_jumpers no)
		(fp_line
			(start -0.299974 0.150114)
			(end -0.299974 -0.150114)
			(stroke
				(width 0.1)
				(type default)
			)
			(layer "F.Fab")
		)
		(fp_line
			(start 0.299974 0.150114)
			(end -0.299974 0.150114)
			(stroke
				(width 0.1)
				(type default)
			)
			(layer "F.Fab")
		)
		(fp_line
			(start -0.299974 -0.150114)
			(end 0.299974 -0.150114)
			(stroke
				(width 0.1)
				(type default)
			)
			(layer "F.Fab")
		)
		(fp_line
			(start 0.299974 -0.150114)
			(end 0.299974 0.150114)
			(stroke
				(width 0.1)
				(type default)
			)
			(layer "F.Fab")
		)
		(pad "1" smd rect
			(at -0.2667 0 270)
			(size 0.3048 0.381)
			(layers "F.Cu" "F.Mask" "F.Paste")
			(net "P1V8_PLL0_PEX3")
		)
		(pad "2" smd rect
			(at 0.2667 0 270)
			(size 0.3048 0.381)
			(layers "F.Cu" "F.Mask" "F.Paste")
			(net "GND")
		)
	)
	(footprint ""
		(layer "F.Cu")
		(at 241.64671 -152.859994 180)
		(property "Reference" "PR7023"
			(at 0 0 180)
			(layer "F.SilkS")
			(hide yes)
			(effects
				(font
					(size 1.27 1.27)
				)
			)
		)
		(property "Value" ""
			(at 0 0 180)
			(layer "F.Fab")
			(effects
				(font
					(size 1.27 1.27)
				)
			)
		)
		(duplicate_pad_numbers_are_jumpers no)
		(fp_line
			(start 1.2954 0.5842)
			(end -1.2954 0.5842)
			(stroke
				(width 0.1524)
				(type default)
			)
			(layer "F.SilkS")
		)
		(fp_line
			(start 1.2954 -0.5842)
			(end 1.2954 0.5842)
			(stroke
				(width 0.1524)
				(type default)
			)
			(layer "F.SilkS")
		)
		(fp_line
			(start -1.2954 0.5842)
			(end -1.2954 -0.5842)
			(stroke
				(width 0.1524)
				(type default)
			)
			(layer "F.SilkS")
		)
		(fp_line
			(start -1.2954 -0.5842)
			(end 1.2954 -0.5842)
			(stroke
				(width 0.1524)
				(type default)
			)
			(layer "F.SilkS")
		)
		(fp_line
			(start 1.1938 0.4064)
			(end 0.8636 0.4064)
			(stroke
				(width 0.1)
				(type default)
			)
			(layer "F.Fab")
		)
		(fp_line
			(start 1.1938 -0.406654)
			(end 1.1938 0.4064)
			(stroke
				(width 0.1)
				(type default)
			)
			(layer "F.Fab")
		)
		(fp_line
			(start 0.8636 0.4572)
			(end -0.8636 0.4572)
			(stroke
				(width 0.1)
				(type default)
			)
			(layer "F.Fab")
		)
		(fp_line
			(start 0.8636 0.4064)
			(end 0.8636 0.4572)
			(stroke
				(width 0.1)
				(type default)
			)
			(layer "F.Fab")
		)
		(fp_line
			(start 0.8636 -0.406654)
			(end 1.1938 -0.406654)
			(stroke
				(width 0.1)
				(type default)
			)
			(layer "F.Fab")
		)
		(fp_line
			(start 0.8636 -0.4572)
			(end 0.8636 -0.406654)
			(stroke
				(width 0.1)
				(type default)
			)
			(layer "F.Fab")
		)
		(fp_line
			(start -0.8636 0.4572)
			(end -0.8636 0.4318)
			(stroke
				(width 0.1)
				(type default)
			)
			(layer "F.Fab")
		)
		(fp_line
			(start -0.8636 0.4318)
			(end -0.8636 0.4064)
			(stroke
				(width 0.1)
				(type default)
			)
			(layer "F.Fab")
		)
		(fp_line
			(start -0.8636 0.4064)
			(end -1.1938 0.4064)
			(stroke
				(width 0.1)
				(type default)
			)
			(layer "F.Fab")
		)
		(fp_line
			(start -0.8636 -0.406654)
			(end -0.8636 -0.4572)
			(stroke
				(width 0.1)
				(type default)
			)
			(layer "F.Fab")
		)
		(fp_line
			(start -0.8636 -0.4572)
			(end 0.8636 -0.4572)
			(stroke
				(width 0.1)
				(type default)
			)
			(layer "F.Fab")
		)
		(fp_line
			(start -1.1938 0.4064)
			(end -1.1938 -0.406654)
			(stroke
				(width 0.1)
				(type default)
			)
			(layer "F.Fab")
		)
		(fp_line
			(start -1.1938 -0.406654)
			(end -0.8636 -0.406654)
			(stroke
				(width 0.1)
				(type default)
			)
			(layer "F.Fab")
		)
		(pad "1" smd rect
			(at -0.7366 0 90)
			(size 0.7112 0.8128)
			(layers "F.Cu" "F.Mask" "F.Paste")
			(net "P12V_NIC4_CO_AVIN_PD")
		)
		(pad "2" smd rect
			(at 0.7366 0 90)
			(size 0.7112 0.8128)
			(layers "F.Cu" "F.Mask" "F.Paste")
			(net "P12V_AUX")
		)
	)
	(footprint ""
		(layer "F.Cu")
		(at 115.281456 -303.649634 90)
		(property "Reference" "PC85"
			(at 0 0 90)
			(layer "F.SilkS")
			(hide yes)
			(effects
				(font
					(size 1.27 1.27)
				)
			)
		)
		(property "Value" ""
			(at 0 0 90)
			(layer "F.Fab")
			(effects
				(font
					(size 1.27 1.27)
				)
			)
		)
		(duplicate_pad_numbers_are_jumpers no)
		(fp_line
			(start 1.524 -0.762)
			(end 1.524 0.762)
			(stroke
				(width 0.1524)
				(type default)
			)
			(layer "F.SilkS")
		)
		(fp_line
			(start -1.524 -0.762)
			(end 1.524 -0.762)
			(stroke
				(width 0.1524)
				(type default)
			)
			(layer "F.SilkS")
		)
		(fp_line
			(start 1.524 0.762)
			(end -1.524 0.762)
			(stroke
				(width 0.1524)
				(type default)
			)
			(layer "F.SilkS")
		)
		(fp_line
			(start -1.524 0.762)
			(end -1.524 -0.762)
			(stroke
				(width 0.1524)
				(type default)
			)
			(layer "F.SilkS")
		)
		(fp_line
			(start 1.1049 -0.724916)
			(end -1.1049 -0.724916)
			(stroke
				(width 0.1)
				(type default)
			)
			(layer "F.Fab")
		)
		(fp_line
			(start -1.1049 -0.724916)
			(end -1.1049 0.724916)
			(stroke
				(width 0.1)
				(type default)
			)
			(layer "F.Fab")
		)
		(fp_line
			(start 1.1049 0.724916)
			(end 1.1049 -0.724916)
			(stroke
				(width 0.1)
				(type default)
			)
			(layer "F.Fab")
		)
		(fp_line
			(start -1.1049 0.724916)
			(end 1.1049 0.724916)
			(stroke
				(width 0.1)
				(type default)
			)
			(layer "F.Fab")
		)
		(pad "1" smd rect
			(at -0.889 0 270)
			(size 1.016 1.27)
			(layers "F.Cu" "F.Mask" "F.Paste")
			(net "P0V8_PEX0")
		)
		(pad "2" smd rect
			(at 0.889 0 270)
			(size 1.016 1.27)
			(layers "F.Cu" "F.Mask" "F.Paste")
			(net "GND")
		)
	)
	(footprint ""
		(layer "F.Cu")
		(at 129.864612 -162.003994 90)
		(property "Reference" "PC634"
			(at 0 0 90)
			(layer "F.SilkS")
			(hide yes)
			(effects
				(font
					(size 1.27 1.27)
				)
			)
		)
		(property "Value" ""
			(at 0 0 90)
			(layer "F.Fab")
			(effects
				(font
					(size 1.27 1.27)
				)
			)
		)
		(duplicate_pad_numbers_are_jumpers no)
		(fp_line
			(start 0.7874 -0.4064)
			(end 0.7874 0.4064)
			(stroke
				(width 0.1524)
				(type default)
			)
			(layer "F.SilkS")
		)
		(fp_line
			(start -0.7874 -0.4064)
			(end 0.7874 -0.4064)
			(stroke
				(width 0.1524)
				(type default)
			)
			(layer "F.SilkS")
		)
		(fp_line
			(start 0.7874 0.4064)
			(end -0.7874 0.4064)
			(stroke
				(width 0.1524)
				(type default)
			)
			(layer "F.SilkS")
		)
		(fp_line
			(start -0.7874 0.4064)
			(end -0.7874 -0.4064)
			(stroke
				(width 0.1524)
				(type default)
			)
			(layer "F.SilkS")
		)
		(fp_line
			(start -0.12065 -0.305054)
			(end -0.12065 -0.2794)
			(stroke
				(width 0.1)
				(type default)
			)
			(layer "F.Fab")
		)
		(fp_line
			(start -0.67945 -0.305054)
			(end -0.12065 -0.305054)
			(stroke
				(width 0.1)
				(type default)
			)
			(layer "F.Fab")
		)
		(fp_line
			(start 0.67945 -0.3048)
			(end 0.67945 0.3048)
			(stroke
				(width 0.1)
				(type default)
			)
			(layer "F.Fab")
		)
		(fp_line
			(start 0.12065 -0.3048)
			(end 0.67945 -0.3048)
			(stroke
				(width 0.1)
				(type default)
			)
			(layer "F.Fab")
		)
		(fp_line
			(start 0.12065 -0.2794)
			(end 0.12065 -0.3048)
			(stroke
				(width 0.1)
				(type default)
			)
			(layer "F.Fab")
		)
		(fp_line
			(start -0.12065 -0.2794)
			(end 0.12065 -0.2794)
			(stroke
				(width 0.1)
				(type default)
			)
			(layer "F.Fab")
		)
		(fp_line
			(start 0.120396 0.2794)
			(end -0.12065 0.2794)
			(stroke
				(width 0.1)
				(type default)
			)
			(layer "F.Fab")
		)
		(fp_line
			(start -0.12065 0.2794)
			(end -0.12065 0.3048)
			(stroke
				(width 0.1)
				(type default)
			)
			(layer "F.Fab")
		)
		(fp_line
			(start 0.67945 0.3048)
			(end 0.120396 0.3048)
			(stroke
				(width 0.1)
				(type default)
			)
			(layer "F.Fab")
		)
		(fp_line
			(start 0.120396 0.3048)
			(end 0.120396 0.2794)
			(stroke
				(width 0.1)
				(type default)
			)
			(layer "F.Fab")
		)
		(fp_line
			(start -0.12065 0.3048)
			(end -0.67945 0.3048)
			(stroke
				(width 0.1)
				(type default)
			)
			(layer "F.Fab")
		)
		(fp_line
			(start -0.67945 0.3048)
			(end -0.67945 -0.305054)
			(stroke
				(width 0.1)
				(type default)
			)
			(layer "F.Fab")
		)
		(pad "1" smd circle
			(at -0.40005 0 90)
			(size 0 0)
			(layers "F.Cu" "F.Mask" "F.Paste")
			(net "P12V_NIC2_CO_TIMER")
		)
		(pad "2" smd circle
			(at 0.40005 0 90)
			(size 0 0)
			(layers "F.Cu" "F.Mask" "F.Paste")
			(net "GND")
		)
	)
	(footprint ""
		(layer "F.Cu")
		(at 13.649198 -304.39487 -90)
		(property "Reference" "PR167"
			(at 0 0 270)
			(layer "F.SilkS")
			(hide yes)
			(effects
				(font
					(size 1.27 1.27)
				)
			)
		)
		(property "Value" ""
			(at 0 0 270)
			(layer "F.Fab")
			(effects
				(font
					(size 1.27 1.27)
				)
			)
		)
		(duplicate_pad_numbers_are_jumpers no)
		(fp_line
			(start -0.7874 0.4064)
			(end -0.7874 -0.4064)
			(stroke
				(width 0.1524)
				(type default)
			)
			(layer "F.SilkS")
		)
		(fp_line
			(start 0.7874 0.4064)
			(end -0.7874 0.4064)
			(stroke
				(width 0.1524)
				(type default)
			)
			(layer "F.SilkS")
		)
		(fp_line
			(start -0.7874 -0.4064)
			(end 0.7874 -0.4064)
			(stroke
				(width 0.1524)
				(type default)
			)
			(layer "F.SilkS")
		)
		(fp_line
			(start 0.7874 -0.4064)
			(end 0.7874 0.4064)
			(stroke
				(width 0.1524)
				(type default)
			)
			(layer "F.SilkS")
		)
		(fp_line
			(start -0.67945 0.3048)
			(end -0.67945 -0.305054)
			(stroke
				(width 0.1)
				(type default)
			)
			(layer "F.Fab")
		)
		(fp_line
			(start -0.12065 0.3048)
			(end -0.67945 0.3048)
			(stroke
				(width 0.1)
				(type default)
			)
			(layer "F.Fab")
		)
		(fp_line
			(start 0.120396 0.3048)
			(end 0.120396 0.2794)
			(stroke
				(width 0.1)
				(type default)
			)
			(layer "F.Fab")
		)
		(fp_line
			(start 0.67945 0.3048)
			(end 0.120396 0.3048)
			(stroke
				(width 0.1)
				(type default)
			)
			(layer "F.Fab")
		)
		(fp_line
			(start -0.12065 0.2794)
			(end -0.12065 0.3048)
			(stroke
				(width 0.1)
				(type default)
			)
			(layer "F.Fab")
		)
		(fp_line
			(start 0.120396 0.2794)
			(end -0.12065 0.2794)
			(stroke
				(width 0.1)
				(type default)
			)
			(layer "F.Fab")
		)
		(fp_line
			(start -0.12065 -0.2794)
			(end 0.12065 -0.2794)
			(stroke
				(width 0.1)
				(type default)
			)
			(layer "F.Fab")
		)
		(fp_line
			(start 0.12065 -0.2794)
			(end 0.12065 -0.3048)
			(stroke
				(width 0.1)
				(type default)
			)
			(layer "F.Fab")
		)
		(fp_line
			(start 0.12065 -0.3048)
			(end 0.67945 -0.3048)
			(stroke
				(width 0.1)
				(type default)
			)
			(layer "F.Fab")
		)
		(fp_line
			(start 0.67945 -0.3048)
			(end 0.67945 0.3048)
			(stroke
				(width 0.1)
				(type default)
			)
			(layer "F.Fab")
		)
		(fp_line
			(start -0.67945 -0.305054)
			(end -0.12065 -0.305054)
			(stroke
				(width 0.1)
				(type default)
			)
			(layer "F.Fab")
		)
		(fp_line
			(start -0.12065 -0.305054)
			(end -0.12065 -0.2794)
			(stroke
				(width 0.1)
				(type default)
			)
			(layer "F.Fab")
		)
		(pad "1" smd circle
			(at -0.40005 0 270)
			(size 0 0)
			(layers "F.Cu" "F.Mask" "F.Paste")
			(net "P1V25_PEX0_CS")
		)
		(pad "2" smd circle
			(at 0.40005 0 270)
			(size 0 0)
			(layers "F.Cu" "F.Mask" "F.Paste")
			(net "GND")
		)
	)
	(footprint ""
		(layer "F.Cu")
		(at 242.310412 -122.931428 180)
		(property "Reference" "PC493"
			(at 0 0 180)
			(layer "F.SilkS")
			(hide yes)
			(effects
				(font
					(size 1.27 1.27)
				)
			)
		)
		(property "Value" ""
			(at 0 0 180)
			(layer "F.Fab")
			(effects
				(font
					(size 1.27 1.27)
				)
			)
		)
		(duplicate_pad_numbers_are_jumpers no)
		(fp_line
			(start 0.7874 0.4064)
			(end -0.7874 0.4064)
			(stroke
				(width 0.1524)
				(type default)
			)
			(layer "F.SilkS")
		)
		(fp_line
			(start 0.7874 -0.4064)
			(end 0.7874 0.4064)
			(stroke
				(width 0.1524)
				(type default)
			)
			(layer "F.SilkS")
		)
		(fp_line
			(start -0.7874 0.4064)
			(end -0.7874 -0.4064)
			(stroke
				(width 0.1524)
				(type default)
			)
			(layer "F.SilkS")
		)
		(fp_line
			(start -0.7874 -0.4064)
			(end 0.7874 -0.4064)
			(stroke
				(width 0.1524)
				(type default)
			)
			(layer "F.SilkS")
		)
		(fp_line
			(start 0.67945 0.3048)
			(end 0.120396 0.3048)
			(stroke
				(width 0.1)
				(type default)
			)
			(layer "F.Fab")
		)
		(fp_line
			(start 0.67945 -0.3048)
			(end 0.67945 0.3048)
			(stroke
				(width 0.1)
				(type default)
			)
			(layer "F.Fab")
		)
		(fp_line
			(start 0.12065 -0.2794)
			(end 0.12065 -0.3048)
			(stroke
				(width 0.1)
				(type default)
			)
			(layer "F.Fab")
		)
		(fp_line
			(start 0.12065 -0.3048)
			(end 0.67945 -0.3048)
			(stroke
				(width 0.1)
				(type default)
			)
			(layer "F.Fab")
		)
		(fp_line
			(start 0.120396 0.3048)
			(end 0.120396 0.2794)
			(stroke
				(width 0.1)
				(type default)
			)
			(layer "F.Fab")
		)
		(fp_line
			(start 0.120396 0.2794)
			(end -0.12065 0.2794)
			(stroke
				(width 0.1)
				(type default)
			)
			(layer "F.Fab")
		)
		(fp_line
			(start -0.12065 0.3048)
			(end -0.67945 0.3048)
			(stroke
				(width 0.1)
				(type default)
			)
			(layer "F.Fab")
		)
		(fp_line
			(start -0.12065 0.2794)
			(end -0.12065 0.3048)
			(stroke
				(width 0.1)
				(type default)
			)
			(layer "F.Fab")
		)
		(fp_line
			(start -0.12065 -0.2794)
			(end 0.12065 -0.2794)
			(stroke
				(width 0.1)
				(type default)
			)
			(layer "F.Fab")
		)
		(fp_line
			(start -0.12065 -0.305054)
			(end -0.12065 -0.2794)
			(stroke
				(width 0.1)
				(type default)
			)
			(layer "F.Fab")
		)
		(fp_line
			(start -0.67945 0.3048)
			(end -0.67945 -0.305054)
			(stroke
				(width 0.1)
				(type default)
			)
			(layer "F.Fab")
		)
		(fp_line
			(start -0.67945 -0.305054)
			(end -0.12065 -0.305054)
			(stroke
				(width 0.1)
				(type default)
			)
			(layer "F.Fab")
		)
		(pad "1" smd circle
			(at -0.40005 0 180)
			(size 0 0)
			(layers "F.Cu" "F.Mask" "F.Paste")
			(net "P5V_AUX")
		)
		(pad "2" smd circle
			(at 0.40005 0 180)
			(size 0 0)
			(layers "F.Cu" "F.Mask" "F.Paste")
			(net "GND")
		)
	)
	(footprint ""
		(layer "F.Cu")
		(at 416.402012 -356.244906 90)
		(property "Reference" "C819"
			(at 0 0 90)
			(layer "F.SilkS")
			(hide yes)
			(effects
				(font
					(size 1.27 1.27)
				)
			)
		)
		(property "Value" ""
			(at 0 0 90)
			(layer "F.Fab")
			(effects
				(font
					(size 1.27 1.27)
				)
			)
		)
		(duplicate_pad_numbers_are_jumpers no)
		(fp_line
			(start 0.299974 -0.150114)
			(end 0.299974 0.150114)
			(stroke
				(width 0.1)
				(type default)
			)
			(layer "F.Fab")
		)
		(fp_line
			(start -0.299974 -0.150114)
			(end 0.299974 -0.150114)
			(stroke
				(width 0.1)
				(type default)
			)
			(layer "F.Fab")
		)
		(fp_line
			(start 0.299974 0.150114)
			(end -0.299974 0.150114)
			(stroke
				(width 0.1)
				(type default)
			)
			(layer "F.Fab")
		)
		(fp_line
			(start -0.299974 0.150114)
			(end -0.299974 -0.150114)
			(stroke
				(width 0.1)
				(type default)
			)
			(layer "F.Fab")
		)
		(pad "1" smd rect
			(at -0.2667 0 90)
			(size 0.3048 0.381)
			(layers "F.Cu" "F.Mask" "F.Paste")
			(net "P5E_PEX3_STN7_TX_DN<115>")
		)
		(pad "2" smd rect
			(at 0.2667 0 90)
			(size 0.3048 0.381)
			(layers "F.Cu" "F.Mask" "F.Paste")
			(net "P5E_PEX3_STN7_TX_C_DN<115>")
		)
	)
	(footprint ""
		(layer "F.Cu")
		(at 385.48564 -115.2652 90)
		(property "Reference" "R350"
			(at 0 0 90)
			(layer "F.SilkS")
			(hide yes)
			(effects
				(font
					(size 1.27 1.27)
				)
			)
		)
		(property "Value" ""
			(at 0 0 90)
			(layer "F.Fab")
			(effects
				(font
					(size 1.27 1.27)
				)
			)
		)
		(duplicate_pad_numbers_are_jumpers no)
		(fp_line
			(start 0.7874 -0.4064)
			(end 0.7874 0.4064)
			(stroke
				(width 0.1524)
				(type default)
			)
			(layer "F.SilkS")
		)
		(fp_line
			(start -0.7874 -0.4064)
			(end 0.7874 -0.4064)
			(stroke
				(width 0.1524)
				(type default)
			)
			(layer "F.SilkS")
		)
		(fp_line
			(start 0.7874 0.4064)
			(end -0.7874 0.4064)
			(stroke
				(width 0.1524)
				(type default)
			)
			(layer "F.SilkS")
		)
		(fp_line
			(start -0.7874 0.4064)
			(end -0.7874 -0.4064)
			(stroke
				(width 0.1524)
				(type default)
			)
			(layer "F.SilkS")
		)
		(fp_line
			(start -0.12065 -0.305054)
			(end -0.12065 -0.2794)
			(stroke
				(width 0.1)
				(type default)
			)
			(layer "F.Fab")
		)
		(fp_line
			(start -0.67945 -0.305054)
			(end -0.12065 -0.305054)
			(stroke
				(width 0.1)
				(type default)
			)
			(layer "F.Fab")
		)
		(fp_line
			(start 0.67945 -0.3048)
			(end 0.67945 0.3048)
			(stroke
				(width 0.1)
				(type default)
			)
			(layer "F.Fab")
		)
		(fp_line
			(start 0.12065 -0.3048)
			(end 0.67945 -0.3048)
			(stroke
				(width 0.1)
				(type default)
			)
			(layer "F.Fab")
		)
		(fp_line
			(start 0.12065 -0.2794)
			(end 0.12065 -0.3048)
			(stroke
				(width 0.1)
				(type default)
			)
			(layer "F.Fab")
		)
		(fp_line
			(start -0.12065 -0.2794)
			(end 0.12065 -0.2794)
			(stroke
				(width 0.1)
				(type default)
			)
			(layer "F.Fab")
		)
		(fp_line
			(start 0.120396 0.2794)
			(end -0.12065 0.2794)
			(stroke
				(width 0.1)
				(type default)
			)
			(layer "F.Fab")
		)
		(fp_line
			(start -0.12065 0.2794)
			(end -0.12065 0.3048)
			(stroke
				(width 0.1)
				(type default)
			)
			(layer "F.Fab")
		)
		(fp_line
			(start 0.67945 0.3048)
			(end 0.120396 0.3048)
			(stroke
				(width 0.1)
				(type default)
			)
			(layer "F.Fab")
		)
		(fp_line
			(start 0.120396 0.3048)
			(end 0.120396 0.2794)
			(stroke
				(width 0.1)
				(type default)
			)
			(layer "F.Fab")
		)
		(fp_line
			(start -0.12065 0.3048)
			(end -0.67945 0.3048)
			(stroke
				(width 0.1)
				(type default)
			)
			(layer "F.Fab")
		)
		(fp_line
			(start -0.67945 0.3048)
			(end -0.67945 -0.305054)
			(stroke
				(width 0.1)
				(type default)
			)
			(layer "F.Fab")
		)
		(pad "1" smd circle
			(at -0.40005 0 90)
			(size 0 0)
			(layers "F.Cu" "F.Mask" "F.Paste")
			(net "P3V3_AUX")
		)
		(pad "2" smd circle
			(at 0.40005 0 90)
			(size 0 0)
			(layers "F.Cu" "F.Mask" "F.Paste")
			(net "HP_NIC6_EN")
		)
	)
)
